(kicad_pcb
	(version 20241229)
	(generator "pcbnew")
	(generator_version "9.0")
	(general
		(thickness 1.711)
		(legacy_teardrops no)
	)
	(paper "A4")
	(title_block
		(title "Antmicro Baseboard for Jetson AGX Thor")
		(date "2026-02-18")
		(rev "1.1.0")
		(company "Antmicro Ltd")
		(comment 1 "www.antmicro.com")
		(comment 9 "footprints 316-319 of 1170")
	)
	(layers
		(0 "F.Cu" signal)
		(4 "In1.Cu" signal)
		(6 "In2.Cu" signal)
		(8 "In3.Cu" signal)
		(10 "In4.Cu" jumper)
		(12 "In5.Cu" signal)
		(14 "In6.Cu" signal)
		(16 "In7.Cu" signal)
		(18 "In8.Cu" signal)
		(2 "B.Cu" signal)
		(9 "F.Adhes" user "F.Adhesive")
		(11 "B.Adhes" user "B.Adhesive")
		(13 "F.Paste" user)
		(15 "B.Paste" user)
		(5 "F.SilkS" user "F.Silkscreen")
		(7 "B.SilkS" user "B.Silkscreen")
		(1 "F.Mask" user)
		(3 "B.Mask" user)
		(17 "Dwgs.User" user "User.Drawings")
		(19 "Cmts.User" user "User.Comments")
		(21 "Eco1.User" user "User.Eco1")
		(23 "Eco2.User" user "User.Eco2")
		(25 "Edge.Cuts" user)
		(27 "Margin" user)
		(31 "F.CrtYd" user "F.Courtyard")
		(29 "B.CrtYd" user "B.Courtyard")
		(35 "F.Fab" user)
		(33 "B.Fab" user)
	)
	(footprint "antmicro-footprints:C_0402_1005Metric"
		(layer "F.Cu")
		(at 197.22 122.9)
		(descr "Capacitor SMD 0402")
		(tags "capacitor SMD 0402")
		(property "Reference" "C358"
			(at -1.315 -1.8 0)
			(layer "F.SilkS")
			(effects
				(font
					(size 0.7 0.7)
					(thickness 0.15)
				)
				(justify left bottom)
			)
		)
		(property "Value" "C_100n_0402"
			(at -1.022927 2.155213 0)
			(layer "F.Fab")
			(effects
				(font
					(size 0.7 0.7)
					(thickness 0.15)
				)
				(justify left bottom)
			)
		)
		(property "Datasheet" "https://www.murata.com/products/productdetail?partno=GRM155R61H104KE14%23"
			(at 0 0 0)
			(layer "F.Fab")
			(hide yes)
			(effects
				(font
					(size 1.27 1.27)
					(thickness 0.15)
				)
			)
		)
		(property "Description" "SMD Multilayer Ceramic Capacitor, 0.1 µF, 50 V, 0402 [1005 Metric], ± 10%, X5R, GRM Series"
			(at 0 0 0)
			(layer "F.Fab")
			(hide yes)
			(effects
				(font
					(size 1.27 1.27)
					(thickness 0.15)
				)
			)
		)
		(property "MPN" "GRM155R61H104KE14D"
			(at 0 0 0)
			(unlocked yes)
			(layer "F.Fab")
			(hide yes)
			(effects
				(font
					(size 1 1)
					(thickness 0.15)
				)
			)
		)
		(property "Val" "100n"
			(at 0 0 0)
			(unlocked yes)
			(layer "F.Fab")
			(hide yes)
			(effects
				(font
					(size 1 1)
					(thickness 0.15)
				)
			)
		)
		(property "Voltage" "50V"
			(at 0 0 0)
			(unlocked yes)
			(layer "F.Fab")
			(hide yes)
			(effects
				(font
					(size 1 1)
					(thickness 0.15)
				)
			)
		)
		(property "Dielectric" "X5R"
			(at 0 0 0)
			(unlocked yes)
			(layer "F.Fab")
			(hide yes)
			(effects
				(font
					(size 1 1)
					(thickness 0.15)
				)
			)
		)
		(property "Manufacturer" "Murata"
			(at 0 0 0)
			(unlocked yes)
			(layer "F.Fab")
			(hide yes)
			(effects
				(font
					(size 1 1)
					(thickness 0.15)
				)
			)
		)
		(property "License" "Apache-2.0"
			(at 0 0 0)
			(unlocked yes)
			(layer "F.Fab")
			(hide yes)
			(effects
				(font
					(size 1 1)
					(thickness 0.15)
				)
			)
		)
		(property "Author" "Antmicro"
			(at 0 0 0)
			(unlocked yes)
			(layer "F.Fab")
			(hide yes)
			(effects
				(font
					(size 1 1)
					(thickness 0.15)
				)
			)
		)
		(sheetname "/USB Hub/")
		(sheetfile "usb_hub.kicad_sch")
		(attr smd)
		(fp_rect
			(start -0.925 -0.47)
			(end 0.925 0.47)
			(stroke
				(width 0.05)
				(type default)
			)
			(fill no)
			(layer "F.CrtYd")
		)
		(fp_line
			(start -0.494 -0.25)
			(end 0.504 -0.25)
			(stroke
				(width 0.15)
				(type solid)
			)
			(layer "F.Fab")
		)
		(fp_line
			(start -0.494 0.248)
			(end -0.494 -0.25)
			(stroke
				(width 0.15)
				(type solid)
			)
			(layer "F.Fab")
		)
		(fp_line
			(start 0.504 -0.25)
			(end 0.504 0.248)
			(stroke
				(width 0.15)
				(type solid)
			)
			(layer "F.Fab")
		)
		(fp_line
			(start 0.504 0.248)
			(end -0.494 0.248)
			(stroke
				(width 0.15)
				(type solid)
			)
			(layer "F.Fab")
		)
		(fp_text user "${REFERENCE}"
			(at -0.939 4.599 0)
			(layer "F.Fab")
			(effects
				(font
					(size 0.7 0.7)
					(thickness 0.15)
				)
				(justify left bottom)
			)
		)
		(fp_text user "Author: Antmicro"
			(at -0.939 3.399 0)
			(layer "F.Fab")
			(effects
				(font
					(size 0.7 0.7)
					(thickness 0.15)
				)
				(justify left bottom)
			)
		)
		(fp_text user "License: Apache-2.0"
			(at -0.939 5.799 0)
			(layer "F.Fab")
			(effects
				(font
					(size 0.7 0.7)
					(thickness 0.15)
				)
				(justify left bottom)
			)
		)
		(pad "1" smd roundrect
			(at -0.48 0)
			(size 0.59 0.64)
			(layers "F.Cu" "F.Mask" "F.Paste")
			(roundrect_rratio 0.25)
			(net 1 "GND")
			(pintype "passive")
		)
		(pad "2" smd roundrect
			(at 0.48 0)
			(size 0.59 0.64)
			(layers "F.Cu" "F.Mask" "F.Paste")
			(roundrect_rratio 0.25)
			(net 282 "+1V15")
			(pintype "passive")
		)
	)
	(footprint "antmicro-footprints:C_0805_2012Metric"
		(layer "F.Cu")
		(at 113.249999 56.74 -90)
		(descr "Capacitor SMD 0805")
		(tags "capacitor SMD 0805")
		(property "Reference" "C379"
			(at -1.87 0.949999 180)
			(layer "F.SilkS")
			(effects
				(font
					(size 0.7 0.7)
					(thickness 0.15)
				)
				(justify left bottom)
			)
		)
		(property "Value" "C_22u_25V_0805"
			(at -2.055717 1.963152 90)
			(layer "F.Fab")
			(effects
				(font
					(size 0.7 0.7)
					(thickness 0.15)
				)
				(justify right top)
			)
		)
		(property "Datasheet" "https://product.samsungsem.com/mlcc/CL21A226MAYNNN.do"
			(at 0 0 90)
			(layer "F.Fab")
			(hide yes)
			(effects
				(font
					(size 1.27 1.27)
					(thickness 0.15)
				)
			)
		)
		(property "Description" "SMT Multilayer Ceramic Capacitor, 22uF, +/-20%, 25V, X5R, 0805 [2012 Metric]"
			(at 0 0 90)
			(layer "F.Fab")
			(hide yes)
			(effects
				(font
					(size 1.27 1.27)
					(thickness 0.15)
				)
			)
		)
		(property "MPN" "CL21A226MAYNNNE"
			(at 0 0 270)
			(unlocked yes)
			(layer "F.Fab")
			(hide yes)
			(effects
				(font
					(size 1 1)
					(thickness 0.15)
				)
			)
		)
		(property "Manufacturer" "Samsung Electro-Mechanics"
			(at 0 0 270)
			(unlocked yes)
			(layer "F.Fab")
			(hide yes)
			(effects
				(font
					(size 1 1)
					(thickness 0.15)
				)
			)
		)
		(property "License" "Apache-2.0"
			(at 0 0 270)
			(unlocked yes)
			(layer "F.Fab")
			(hide yes)
			(effects
				(font
					(size 1 1)
					(thickness 0.15)
				)
			)
		)
		(property "Author" "Antmicro"
			(at 0 0 270)
			(unlocked yes)
			(layer "F.Fab")
			(hide yes)
			(effects
				(font
					(size 1 1)
					(thickness 0.15)
				)
			)
		)
		(property "Val" "22u"
			(at 0 0 270)
			(unlocked yes)
			(layer "F.Fab")
			(hide yes)
			(effects
				(font
					(size 1 1)
					(thickness 0.15)
				)
			)
		)
		(property "Voltage" "25V"
			(at 0 0 270)
			(unlocked yes)
			(layer "F.Fab")
			(hide yes)
			(effects
				(font
					(size 1 1)
					(thickness 0.15)
				)
			)
		)
		(property "Dielectric" "X5R"
			(at 0 0 270)
			(unlocked yes)
			(layer "F.Fab")
			(hide yes)
			(effects
				(font
					(size 1 1)
					(thickness 0.15)
				)
			)
		)
		(property "Public" "False"
			(at 0 0 270)
			(unlocked yes)
			(layer "F.Fab")
			(hide yes)
			(effects
				(font
					(size 1 1)
					(thickness 0.15)
				)
			)
		)
		(sheetname "/DCDC/")
		(sheetfile "dcdc.kicad_sch")
		(attr smd)
		(fp_line
			(start -0.3 0.7)
			(end 0.3 0.7)
			(stroke
				(width 0.15)
				(type solid)
			)
			(layer "F.SilkS")
		)
		(fp_line
			(start -0.3 -0.7)
			(end 0.3 -0.7)
			(stroke
				(width 0.15)
				(type solid)
			)
			(layer "F.SilkS")
		)
		(fp_rect
			(start 1.95 -0.9)
			(end -1.95 0.9)
			(stroke
				(width 0.05)
				(type default)
			)
			(fill no)
			(layer "F.CrtYd")
		)
		(fp_rect
			(start -0.95 -0.675)
			(end 0.95 0.675)
			(stroke
				(width 0.15)
				(type solid)
			)
			(fill no)
			(layer "F.Fab")
		)
		(fp_text user "Author: Antmicro"
			(at -1.9 5.947 90)
			(layer "F.Fab")
			(effects
				(font
					(size 0.7 0.7)
					(thickness 0.15)
				)
				(justify right top)
			)
		)
		(fp_text user "License: Apache-2.0"
			(at -1.9 4.947 90)
			(layer "F.Fab")
			(effects
				(font
					(size 0.7 0.7)
					(thickness 0.15)
				)
				(justify right top)
			)
		)
		(fp_text user "${REFERENCE}"
			(at -1.9 3.947 90)
			(layer "F.Fab")
			(effects
				(font
					(size 0.7 0.7)
					(thickness 0.15)
				)
				(justify right top)
			)
		)
		(pad "1" smd roundrect
			(at -1.1 0 270)
			(size 1.2 1.3)
			(layers "F.Cu" "F.Mask" "F.Paste")
			(roundrect_rratio 0.25)
			(net 1 "GND")
			(pintype "passive")
		)
		(pad "2" smd roundrect
			(at 1.1 0 270)
			(size 1.2 1.3)
			(layers "F.Cu" "F.Mask" "F.Paste")
			(roundrect_rratio 0.25)
			(net 1278 "/DCDC/5V_{AON}_OUT")
			(pintype "passive")
		)
	)
	(footprint "antmicro-footprints:C_0805_2012Metric"
		(layer "F.Cu")
		(at 176.13 110.356 90)
		(descr "Capacitor SMD 0805")
		(tags "capacitor SMD 0805")
		(property "Reference" "C45"
			(at 1.92 -0.16 90)
			(layer "F.SilkS")
			(effects
				(font
					(size 0.7 0.7)
					(thickness 0.15)
				)
				(justify left bottom)
			)
		)
		(property "Value" "C_22u_25V_0805"
			(at -2.055717 1.963152 90)
			(layer "F.Fab")
			(effects
				(font
					(size 0.7 0.7)
					(thickness 0.15)
				)
				(justify left bottom)
			)
		)
		(property "Datasheet" "https://product.samsungsem.com/mlcc/CL21A226MAYNNN.do"
			(at 0 0 90)
			(layer "F.Fab")
			(hide yes)
			(effects
				(font
					(size 1.27 1.27)
					(thickness 0.15)
				)
			)
		)
		(property "Description" "SMT Multilayer Ceramic Capacitor, 22uF, +/-20%, 25V, X5R, 0805 [2012 Metric]"
			(at 0 0 90)
			(layer "F.Fab")
			(hide yes)
			(effects
				(font
					(size 1.27 1.27)
					(thickness 0.15)
				)
			)
		)
		(property "MPN" "CL21A226MAYNNNE"
			(at 0 0 90)
			(unlocked yes)
			(layer "F.Fab")
			(hide yes)
			(effects
				(font
					(size 1 1)
					(thickness 0.15)
				)
			)
		)
		(property "Manufacturer" "Samsung Electro-Mechanics"
			(at 0 0 90)
			(unlocked yes)
			(layer "F.Fab")
			(hide yes)
			(effects
				(font
					(size 1 1)
					(thickness 0.15)
				)
			)
		)
		(property "License" "Apache-2.0"
			(at 0 0 90)
			(unlocked yes)
			(layer "F.Fab")
			(hide yes)
			(effects
				(font
					(size 1 1)
					(thickness 0.15)
				)
			)
		)
		(property "Author" "Antmicro"
			(at 0 0 90)
			(unlocked yes)
			(layer "F.Fab")
			(hide yes)
			(effects
				(font
					(size 1 1)
					(thickness 0.15)
				)
			)
		)
		(property "Val" "22u"
			(at 0 0 90)
			(unlocked yes)
			(layer "F.Fab")
			(hide yes)
			(effects
				(font
					(size 1 1)
					(thickness 0.15)
				)
			)
		)
		(property "Voltage" "25V"
			(at 0 0 90)
			(unlocked yes)
			(layer "F.Fab")
			(hide yes)
			(effects
				(font
					(size 1 1)
					(thickness 0.15)
				)
			)
		)
		(property "Dielectric" "X5R"
			(at 0 0 90)
			(unlocked yes)
			(layer "F.Fab")
			(hide yes)
			(effects
				(font
					(size 1 1)
					(thickness 0.15)
				)
			)
		)
		(property "Public" "False"
			(at 0 0 90)
			(unlocked yes)
			(layer "F.Fab")
			(hide yes)
			(effects
				(font
					(size 1 1)
					(thickness 0.15)
				)
			)
		)
		(sheetname "/DCDC/")
		(sheetfile "dcdc.kicad_sch")
		(attr smd)
		(fp_line
			(start -0.3 -0.7)
			(end 0.3 -0.7)
			(stroke
				(width 0.15)
				(type solid)
			)
			(layer "F.SilkS")
		)
		(fp_line
			(start -0.3 0.7)
			(end 0.3 0.7)
			(stroke
				(width 0.15)
				(type solid)
			)
			(layer "F.SilkS")
		)
		(fp_rect
			(start 1.95 -0.9)
			(end -1.95 0.9)
			(stroke
				(width 0.05)
				(type default)
			)
			(fill no)
			(layer "F.CrtYd")
		)
		(fp_rect
			(start -0.95 -0.675)
			(end 0.95 0.675)
			(stroke
				(width 0.15)
				(type solid)
			)
			(fill no)
			(layer "F.Fab")
		)
		(fp_text user "${REFERENCE}"
			(at -1.9 3.947 90)
			(layer "F.Fab")
			(effects
				(font
					(size 0.7 0.7)
					(thickness 0.15)
				)
				(justify left bottom)
			)
		)
		(fp_text user "License: Apache-2.0"
			(at -1.9 4.947 90)
			(layer "F.Fab")
			(effects
				(font
					(size 0.7 0.7)
					(thickness 0.15)
				)
				(justify left bottom)
			)
		)
		(fp_text user "Author: Antmicro"
			(at -1.9 5.947 90)
			(layer "F.Fab")
			(effects
				(font
					(size 0.7 0.7)
					(thickness 0.15)
				)
				(justify left bottom)
			)
		)
		(pad "1" smd roundrect
			(at -1.1 0 90)
			(size 1.2 1.3)
			(layers "F.Cu" "F.Mask" "F.Paste")
			(roundrect_rratio 0.25)
			(net 1 "GND")
			(pintype "passive")
		)
		(pad "2" smd roundrect
			(at 1.1 0 90)
			(size 1.2 1.3)
			(layers "F.Cu" "F.Mask" "F.Paste")
			(roundrect_rratio 0.25)
			(net 13 "VCC")
			(pintype "passive")
		)
	)
	(footprint "antmicro-footprints:L_Coilcraft-XAL7070"
		(layer "F.Cu")
		(at 180 97.5 180)
		(property "Reference" "L3"
			(at -4.234468 -2.855 90)
			(layer "F.SilkS")
			(effects
				(font
					(size 0.7 0.7)
					(thickness 0.15)
				)
				(justify right top)
			)
		)
		(property "Value" "L_3u3_15.1A_Coilcraft-XAL7070"
			(at 0 5.2 0)
			(layer "F.Fab")
			(effects
				(font
					(size 0.7 0.7)
					(thickness 0.15)
				)
				(justify right top)
			)
		)
		(property "Datasheet" "https://www.coilcraft.com/en-us/products/power/shielded-inductors/molded-inductor/xal/xal7070/xal7070-332/"
			(at 0 0 0)
			(layer "F.Fab")
			(hide yes)
			(effects
				(font
					(size 1.27 1.27)
					(thickness 0.15)
				)
			)
		)
		(property "Description" "Power Inductor (SMD), 3.3 µH, 15.1 A, Shielded, 19.4 A, XAL7070"
			(at 0 0 0)
			(layer "F.Fab")
			(hide yes)
			(effects
				(font
					(size 1.27 1.27)
					(thickness 0.15)
				)
			)
		)
		(property "Val" "3u3/15.1A"
			(at 0 0 180)
			(unlocked yes)
			(layer "F.Fab")
			(hide yes)
			(effects
				(font
					(size 1 1)
					(thickness 0.15)
				)
			)
		)
		(property "Manufacturer" "Coilcraft"
			(at 0 0 180)
			(unlocked yes)
			(layer "F.Fab")
			(hide yes)
			(effects
				(font
					(size 1 1)
					(thickness 0.15)
				)
			)
		)
		(property "MPN" "XAL7070-332MEB"
			(at 0 0 180)
			(unlocked yes)
			(layer "F.Fab")
			(hide yes)
			(effects
				(font
					(size 1 1)
					(thickness 0.15)
				)
			)
		)
		(property "ISat" "19.4 A"
			(at 0 0 180)
			(unlocked yes)
			(layer "F.Fab")
			(hide yes)
			(effects
				(font
					(size 1 1)
					(thickness 0.15)
				)
			)
		)
		(property "IMax" "15.1 A"
			(at 0 0 180)
			(unlocked yes)
			(layer "F.Fab")
			(hide yes)
			(effects
				(font
					(size 1 1)
					(thickness 0.15)
				)
			)
		)
		(property "Size" "7.7x8"
			(at 0 0 180)
			(unlocked yes)
			(layer "F.Fab")
			(hide yes)
			(effects
				(font
					(size 1 1)
					(thickness 0.15)
				)
			)
		)
		(property "Author" "Antmicro"
			(at 0 0 180)
			(unlocked yes)
			(layer "F.Fab")
			(hide yes)
			(effects
				(font
					(size 1 1)
					(thickness 0.15)
				)
			)
		)
		(property "License" "Apache-2.0"
			(at 0 0 180)
			(unlocked yes)
			(layer "F.Fab")
			(hide yes)
			(effects
				(font
					(size 1 1)
					(thickness 0.15)
				)
			)
		)
		(component_classes
			(class "DCDC_SOM")
		)
		(sheetname "/DCDC/")
		(sheetfile "dcdc.kicad_sch")
		(attr smd)
		(fp_line
			(start 3.85 -4)
			(end 3.85 4)
			(stroke
				(width 0.15)
				(type solid)
			)
			(layer "F.SilkS")
		)
		(fp_line
			(start 3.85 -4)
			(end -3.85 -4)
			(stroke
				(width 0.15)
				(type solid)
			)
			(layer "F.SilkS")
		)
		(fp_line
			(start -3.85 4)
			(end 3.85 4)
			(stroke
				(width 0.15)
				(type solid)
			)
			(layer "F.SilkS")
		)
		(fp_line
			(start -3.85 4)
			(end -3.85 -4)
			(stroke
				(width 0.15)
				(type solid)
			)
			(layer "F.SilkS")
		)
		(fp_rect
			(start -4.09 -4.25)
			(end 4.09 4.25)
			(stroke
				(width 0.05)
				(type solid)
			)
			(fill no)
			(layer "F.CrtYd")
		)
		(fp_line
			(start 3.85 4)
			(end -3.85 4)
			(stroke
				(width 0.15)
				(type solid)
			)
			(layer "F.Fab")
		)
		(fp_line
			(start 3.85 -4)
			(end 3.85 4)
			(stroke
				(width 0.15)
				(type solid)
			)
			(layer "F.Fab")
		)
		(fp_line
			(start -3.85 4)
			(end -3.85 -4)
			(stroke
				(width 0.15)
				(type solid)
			)
			(layer "F.Fab")
		)
		(fp_line
			(start -3.85 -4)
			(end 3.85 -4)
			(stroke
				(width 0.15)
				(type solid)
			)
			(layer "F.Fab")
		)
		(fp_text user "Author: Antmicro"
			(at -4.09 7.2 0)
			(layer "F.Fab")
			(effects
				(font
					(size 0.7 0.7)
					(thickness 0.15)
				)
				(justify right top)
			)
		)
		(fp_text user "License: Apache-2.0"
			(at -4.09 9.6 0)
			(layer "F.Fab")
			(effects
				(font
					(size 0.7 0.7)
					(thickness 0.15)
				)
				(justify right top)
			)
		)
		(fp_text user "${REFERENCE}"
			(at -4.09 8.4 0)
			(layer "F.Fab")
			(effects
				(font
					(size 0.7 0.7)
					(thickness 0.15)
				)
				(justify right top)
			)
		)
		(pad "1" smd roundrect
			(at -2.41 0 180)
			(size 1.92 6.5)
			(layers "F.Cu" "F.Mask" "F.Paste")
			(roundrect_rratio 0.1)
			(net 1183 "/DCDC/16V_SW")
			(pintype "passive")
		)
		(pad "2" smd roundrect
			(at 2.41 0 180)
			(size 1.92 6.5)
			(layers "F.Cu" "F.Mask" "F.Paste")
			(roundrect_rratio 0.1)
			(net 903 "/DCDC/16V_OUT")
			(pintype "passive")
		)
	)
)
